
INPUT-UNITS     INCHES

WHEEL     1

CIRCLE           187            D10
FLASH     TR183X197X40-45      0.00000  D11
CIRCLE           315            D12
CIRCLE           237            D13
CIRCLE           319            D14
CIRCLE            26            D15
FLASH     TR_C5-ALL            0.00000  D16
CIRCLE            18            D17
RECTANGLE         26        54   0.00000  D18
RECTANGLE         54        26   0.00000  D19
RECTANGLE         30        58   0.00000  D20
RECTANGLE         58        30   0.00000  D21
RECTANGLE         10        50   0.00000  D22
RECTANGLE         50        10   0.00000  D23
RECTANGLE         14        54   0.00000  D24
RECTANGLE         54        14   0.00000  D25
RECTANGLE         10        32   0.00000  D26
RECTANGLE         32        10   0.00000  D27
RECTANGLE         14        36   0.00000  D28
RECTANGLE         36        14   0.00000  D29
RECTANGLE         22        32   0.00000  D30
RECTANGLE         32        22   0.00000  D31
RECTANGLE         26        36   0.00000  D32
RECTANGLE         36        26   0.00000  D33
RECTANGLE         32        34   0.00000  D34
RECTANGLE         34        32   0.00000  D35
RECTANGLE         36        38   0.00000  D36
RECTANGLE         38        36   0.00000  D37
RECTANGLE         15        46   0.00000  D38
RECTANGLE         46        15   0.00000  D39
RECTANGLE         19        50   0.00000  D40
RECTANGLE         50        19   0.00000  D41
RECTANGLE         11        28   0.00000  D42
RECTANGLE         28        11   0.00000  D43
RECTANGLE         15        32   0.00000  D44
RECTANGLE         32        15   0.00000  D45
RECTANGLE         11        30   0.00000  D46
RECTANGLE         30        11   0.00000  D47
RECTANGLE         15        34   0.00000  D48
RECTANGLE         34        15   0.00000  D49
RECTANGLE         18        20   0.00000  D50
RECTANGLE         20        18   0.00000  D51
RECTANGLE         22        24   0.00000  D52
RECTANGLE         24        22   0.00000  D53
RECTANGLE       84.8       130   0.00000  D54
RECTANGLE        130      84.8   0.00000  D55
RECTANGLE       88.8       134   0.00000  D56
RECTANGLE        134      88.8   0.00000  D57
RECTANGLE         16        44   0.00000  D58
RECTANGLE         44        16   0.00000  D59
RECTANGLE         20        48   0.00000  D60
RECTANGLE         48        20   0.00000  D61
RECTANGLE         67        99   0.00000  D62
RECTANGLE         99        67   0.00000  D63
RECTANGLE         71       103   0.00000  D64
RECTANGLE        103        71   0.00000  D65
RECTANGLE         85        89   0.00000  D66
RECTANGLE         89        85   0.00000  D67
RECTANGLE         89        93   0.00000  D68
RECTANGLE         93        89   0.00000  D69
CIRCLE            62            D70
FLASH     TR58X72X15-45        0.00000  D71
SQUARE            62   0.00000            D72
SQUARE            66   0.00000            D73
CIRCLE            66            D74
CIRCLE            60            D75
FLASH     TR56X70X15-45        0.00000  D76
SQUARE            60   0.00000            D77
SQUARE            64   0.00000            D78
CIRCLE            64            D79
RECTANGLE        116       197   0.00000  D80
RECTANGLE        197       116   0.00000  D81
RECTANGLE        120       201   0.00000  D82
RECTANGLE        201       120   0.00000  D83
RECTANGLE        126       270   0.00000  D84
RECTANGLE        270       126   0.00000  D85
RECTANGLE        130       274   0.00000  D86
RECTANGLE        274       130   0.00000  D87
FLASH     TR172X186X40-45      0.00000  D88
CIRCLE           241            D89
CIRCLE           186            D90
CIRCLE           156            D91
CIRCLE           176            D92
RECTANGLE        128       135   0.00000  D93
RECTANGLE        135       128   0.00000  D94
RECTANGLE        132       139   0.00000  D95
RECTANGLE        139       132   0.00000  D96
CIRCLE           155            D97
FLASH     TR141X155X40-45      0.00000  D98
CIRCLE           125            D99
CIRCLE           145            D100
CIRCLE            87            D101
FLASH     TR83X97X25-45        0.00000  D102
CIRCLE            85            D103
RECTANGLE         17        24   0.00000  D104
RECTANGLE         24        17   0.00000  D105
RECTANGLE         21        28   0.00000  D106
RECTANGLE         28        21   0.00000  D107
RECTANGLE         14        59   0.00000  D108
RECTANGLE         59        14   0.00000  D109
RECTANGLE         18        63   0.00000  D110
RECTANGLE         63        18   0.00000  D111
RECTANGLE         18        52   0.00000  D112
RECTANGLE         52        18   0.00000  D113
RECTANGLE         22        56   0.00000  D114
RECTANGLE         56        22   0.00000  D115
RECTANGLE         22        68   0.00000  D116
RECTANGLE         68        22   0.00000  D117
RECTANGLE         26        72   0.00000  D118
RECTANGLE         72        26   0.00000  D119
RECTANGLE         14        56   0.00000  D120
RECTANGLE         56        14   0.00000  D121
RECTANGLE         18        60   0.00000  D122
RECTANGLE         60        18   0.00000  D123
RECTANGLE         40        63   0.00000  D124
RECTANGLE         63        40   0.00000  D125
RECTANGLE         44        67   0.00000  D126
RECTANGLE         67        44   0.00000  D127
RECTANGLE         32        36   0.00000  D128
RECTANGLE         36        32   0.00000  D129
RECTANGLE         36        40   0.00000  D130
RECTANGLE         40        36   0.00000  D131
RECTANGLE         10        52   0.00000  D132
RECTANGLE         52        10   0.00000  D133
RECTANGLE         10        36   0.00000  D134
RECTANGLE         36        10   0.00000  D135
RECTANGLE         14        40   0.00000  D136
RECTANGLE         40        14   0.00000  D137
CIRCLE            83            D138
FLASH     TR79X93X15-45        0.00000  D139
CIRCLE            93            D140
CIRCLE            97            D141
SQUARE            93   0.00000            D142
SQUARE            97   0.00000            D143
CIRCLE            56            D144
FLASH     TR52X66X15-45        0.00000  D145
CIRCLE            52            D146
CIRCLE           103            D147
FLASH     TR99X113X25-45       0.00000  D148
CIRCLE           123            D149
CIRCLE           127            D150
RECTANGLE        110       220   0.00000  D151
RECTANGLE        220       110   0.00000  D152
RECTANGLE        114       224   0.00000  D153
RECTANGLE        224       114   0.00000  D154
RECTANGLE         59       134   0.00000  D155
RECTANGLE        134        59   0.00000  D156
RECTANGLE         63       138   0.00000  D157
RECTANGLE        138        63   0.00000  D158
LINE              12            D159
OBLONG            12        33   0.00000  D160
OBLONG            33        12   0.00000  D161
LINE              14            D162
OBLONG            14        37   0.00000  D163
OBLONG            37        14   0.00000  D164
RECTANGLE         44        54   0.00000  D165
RECTANGLE         54        44   0.00000  D166
RECTANGLE         48        58   0.00000  D167
RECTANGLE         58        48   0.00000  D168
RECTANGLE         10        20   0.00000  D169
RECTANGLE         20        10   0.00000  D170
RECTANGLE         14        24   0.00000  D171
RECTANGLE         24        14   0.00000  D172
RECTANGLE         52       122   0.00000  D173
RECTANGLE        122        52   0.00000  D174
RECTANGLE         56       126   0.00000  D175
RECTANGLE        126        56   0.00000  D176
RECTANGLE         28        32   0.00000  D177
RECTANGLE         32        28   0.00000  D178
RECTANGLE         99       130   0.00000  D179
RECTANGLE        130        99   0.00000  D180
RECTANGLE        103       134   0.00000  D181
RECTANGLE        134       103   0.00000  D182
RECTANGLE         95       130   0.00000  D183
RECTANGLE        130        95   0.00000  D184
RECTANGLE         99       134   0.00000  D185
RECTANGLE        134        99   0.00000  D186
RECTANGLE         46        62   0.00000  D187
RECTANGLE         62        46   0.00000  D188
RECTANGLE         50        66   0.00000  D189
RECTANGLE         66        50   0.00000  D190
RECTANGLE         40        50   0.00000  D191
RECTANGLE         50        40   0.00000  D192
FLASH     TR62X76X15-45        0.00000  D193
CIRCLE            70            D194
SQUARE            70   0.00000            D195
CIRCLE            61            D196
FLASH     TR57X71X15-45        0.00000  D197
CIRCLE            58            D198
CIRCLE            54            D199
FLASH     TR50X64X15-45        0.00000  D200
SQUARE            50   0.00000            D201
CIRCLE            50            D202
SQUARE            54   0.00000            D203
CIRCLE           117            D204
FLASH     TR103X117X25-45      0.00000  D205
CIRCLE           107            D206
CIRCLE         60.15            D207
FLASH     TR_C38-ALL           0.00000  D208
SQUARE         60.15   0.00000            D209
SQUARE         64.15   0.00000            D210
CIRCLE         64.15            D211
CIRCLE           256            D212
FLASH     TR142X156X40-45      0.00000  D213
CIRCLE           260            D214
CIRCLE           272            D215
FLASH     TR268X282X40-45      0.00000  D216
CIRCLE           400            D217
LINE             394            D218
OBLONG           394      1260   0.00000  D219
OBLONG          1260       394   0.00000  D220
CIRCLE           404            D221
LINE             398            D222
OBLONG           398      1264   0.00000  D223
OBLONG          1264       398   0.00000  D224
FLASH     TR_C10-ALL           0.00000  D225
RECTANGLE         24        28   0.00000  D226
RECTANGLE         28        24   0.00000  D227
CIRCLE            30            D228
CIRCLE            20            D229
CIRCLE            34            D230
CIRCLE            39            D231
CIRCLE           118            D232
LINE               6            D233
LINE               2            D234
LINE               1            D235
LINE              10            D236
LINE             6.8            D237
LINE              40            D238
LINE               4            D239
LINE               8            D240
LINE              25            D241
LINE              20            D242
LINE              80            D243
LINE              15            D244
LINE              18            D245
LINE             100            D246
LINE             240            D247
LINE             120            D248
LINE              35            D249
LINE              11            D250
LINE             5.1            D251
LINE              16            D252
LINE              17            D253

